(kicad_pcb
	(version 20260206)
	(generator "pcbnew")
	(generator_version "10.0")
	(general
		(thickness 1.6)
		(legacy_teardrops no)
	)
	(paper "A4")
	(title_block
		(title "04192023_DAF0TMB3IC0_F0TG_MB_C_brd_V02_OCP.brd")
		(comment 1 "Grand Teton / footprints 4072-4078 of 8354")
	)
	(layers
		(0 "F.Cu" signal "TOP")
		(4 "In1.Cu" signal "GND")
		(6 "In2.Cu" signal "IN1")
		(8 "In3.Cu" signal "GND1")
		(10 "In4.Cu" signal "IN2")
		(12 "In5.Cu" signal "GND2")
		(14 "In6.Cu" signal "IN3")
		(16 "In7.Cu" signal "GND3")
		(18 "In8.Cu" signal "VCC")
		(20 "In9.Cu" signal "VCC1")
		(22 "In10.Cu" signal "GND4")
		(24 "In11.Cu" signal "IN4")
		(26 "In12.Cu" signal "GND5")
		(28 "In13.Cu" signal "IN5")
		(30 "In14.Cu" signal "GND6")
		(32 "In15.Cu" signal "IN6")
		(34 "In16.Cu" signal "GND7")
		(2 "B.Cu" signal "BOTTOM")
		(9 "F.Adhes" user "F.Adhesive")
		(11 "B.Adhes" user "B.Adhesive")
		(13 "F.Paste" user "Package Geometry/Pastemask Top")
		(15 "B.Paste" user "Package Geometry/Pastemask Bottom")
		(5 "F.SilkS" user "Ref Des/Silkscreen Top")
		(7 "B.SilkS" user "Ref Des/Silkscreen Bottom")
		(1 "F.Mask" user "Board Geometry/Soldermask Top")
		(3 "B.Mask" user "Board Geometry/Soldermask Bottom")
		(17 "Dwgs.User" user "User.Drawings")
		(19 "Cmts.User" user "User.Comments")
		(21 "Eco1.User" user "User.Eco1")
		(23 "Eco2.User" user "User.Eco2")
		(25 "Edge.Cuts" user "Board Geometry/Outline")
		(27 "Margin" user)
		(31 "F.CrtYd" user "Package Geometry/Place Bound Top")
		(29 "B.CrtYd" user "Package Geometry/Place Bound Bottom")
		(35 "F.Fab" user "Ref Des/Assembly Top")
		(33 "B.Fab" user "Ref Des/Assembly Bottom")
	)
	(footprint ""
		(layer "F.Cu")
		(at 38.180772 -58.155332 90)
		(property "Reference" "D8001"
			(at -1.781556 1.402334 90)
			(unlocked yes)
			(layer "F.SilkS")
			(effects
				(font
					(size 0.7874 0.5842)
					(thickness 0.1524)
				)
				(justify left)
			)
		)
		(property "Value" ""
			(at 0 0 90)
			(layer "F.Fab")
			(effects
				(font
					(size 1.27 1.27)
				)
			)
		)
		(duplicate_pad_numbers_are_jumpers no)
		(fp_line
			(start 1.16078 -0.4826)
			(end 1.16078 0.4826)
			(stroke
				(width 0.1524)
				(type default)
			)
			(layer "F.SilkS")
		)
		(fp_line
			(start 1.03378 -0.4826)
			(end 1.03378 0.4826)
			(stroke
				(width 0.1524)
				(type default)
			)
			(layer "F.SilkS")
		)
		(fp_line
			(start 0.90678 -0.4826)
			(end 0.90678 0.4826)
			(stroke
				(width 0.1524)
				(type default)
			)
			(layer "F.SilkS")
		)
		(fp_line
			(start -0.64008 -0.4826)
			(end 1.16078 -0.4826)
			(stroke
				(width 0.1524)
				(type default)
			)
			(layer "F.SilkS")
		)
		(fp_line
			(start -0.79248 -0.4826)
			(end 1.03378 -0.4826)
			(stroke
				(width 0.1524)
				(type default)
			)
			(layer "F.SilkS")
		)
		(fp_line
			(start -0.89408 -0.4826)
			(end 0.90678 -0.4826)
			(stroke
				(width 0.1524)
				(type default)
			)
			(layer "F.SilkS")
		)
		(fp_line
			(start 1.16078 0.4826)
			(end -0.64008 0.4826)
			(stroke
				(width 0.1524)
				(type default)
			)
			(layer "F.SilkS")
		)
		(fp_line
			(start 1.03378 0.4826)
			(end -0.79248 0.4826)
			(stroke
				(width 0.1524)
				(type default)
			)
			(layer "F.SilkS")
		)
		(fp_line
			(start 0.90678 0.4826)
			(end -0.90678 0.4826)
			(stroke
				(width 0.1524)
				(type default)
			)
			(layer "F.SilkS")
		)
		(fp_line
			(start -0.90678 0.4826)
			(end -0.90678 -0.4699)
			(stroke
				(width 0.1524)
				(type default)
			)
			(layer "F.SilkS")
		)
		(fp_line
			(start 0.499872 -0.249936)
			(end 0.499872 0.249936)
			(stroke
				(width 0.1)
				(type default)
			)
			(layer "F.Fab")
		)
		(fp_line
			(start -0.499872 -0.249936)
			(end 0.499872 -0.249936)
			(stroke
				(width 0.1)
				(type default)
			)
			(layer "F.Fab")
		)
		(fp_line
			(start 0.499872 0.249936)
			(end -0.499872 0.249936)
			(stroke
				(width 0.1)
				(type default)
			)
			(layer "F.Fab")
		)
		(fp_line
			(start -0.499872 0.249936)
			(end -0.499872 -0.249936)
			(stroke
				(width 0.1)
				(type default)
			)
			(layer "F.Fab")
		)
		(pad "A" smd rect
			(at -0.47498 0 90)
			(size 0.6096 0.7112)
			(layers "F.Cu" "F.Mask" "F.Paste")
			(net "LED_P12V_PSU_R1")
		)
		(pad "C" smd rect
			(at 0.47498 0 90)
			(size 0.6096 0.7112)
			(layers "F.Cu" "F.Mask" "F.Paste")
			(net "GND")
		)
	)
	(footprint ""
		(layer "F.Cu")
		(at 34.103818 -436.433214 180)
		(property "Reference" "R2992"
			(at 0 0 180)
			(layer "F.SilkS")
			(hide yes)
			(effects
				(font
					(size 1.27 1.27)
				)
			)
		)
		(property "Value" ""
			(at 0 0 180)
			(layer "F.Fab")
			(effects
				(font
					(size 1.27 1.27)
				)
			)
		)
		(duplicate_pad_numbers_are_jumpers no)
		(fp_line
			(start 0.7874 0.4064)
			(end -0.7874 0.4064)
			(stroke
				(width 0.1524)
				(type default)
			)
			(layer "F.SilkS")
		)
		(fp_line
			(start 0.7874 -0.4064)
			(end 0.7874 0.4064)
			(stroke
				(width 0.1524)
				(type default)
			)
			(layer "F.SilkS")
		)
		(fp_line
			(start -0.7874 0.4064)
			(end -0.7874 -0.4064)
			(stroke
				(width 0.1524)
				(type default)
			)
			(layer "F.SilkS")
		)
		(fp_line
			(start -0.7874 -0.4064)
			(end 0.7874 -0.4064)
			(stroke
				(width 0.1524)
				(type default)
			)
			(layer "F.SilkS")
		)
		(fp_line
			(start 0.67945 0.3048)
			(end 0.120396 0.3048)
			(stroke
				(width 0.1)
				(type default)
			)
			(layer "F.Fab")
		)
		(fp_line
			(start 0.67945 -0.3048)
			(end 0.67945 0.3048)
			(stroke
				(width 0.1)
				(type default)
			)
			(layer "F.Fab")
		)
		(fp_line
			(start 0.12065 -0.2794)
			(end 0.12065 -0.3048)
			(stroke
				(width 0.1)
				(type default)
			)
			(layer "F.Fab")
		)
		(fp_line
			(start 0.12065 -0.3048)
			(end 0.67945 -0.3048)
			(stroke
				(width 0.1)
				(type default)
			)
			(layer "F.Fab")
		)
		(fp_line
			(start 0.120396 0.3048)
			(end 0.120396 0.2794)
			(stroke
				(width 0.1)
				(type default)
			)
			(layer "F.Fab")
		)
		(fp_line
			(start 0.120396 0.2794)
			(end -0.12065 0.2794)
			(stroke
				(width 0.1)
				(type default)
			)
			(layer "F.Fab")
		)
		(fp_line
			(start -0.12065 0.3048)
			(end -0.67945 0.3048)
			(stroke
				(width 0.1)
				(type default)
			)
			(layer "F.Fab")
		)
		(fp_line
			(start -0.12065 0.2794)
			(end -0.12065 0.3048)
			(stroke
				(width 0.1)
				(type default)
			)
			(layer "F.Fab")
		)
		(fp_line
			(start -0.12065 -0.2794)
			(end 0.12065 -0.2794)
			(stroke
				(width 0.1)
				(type default)
			)
			(layer "F.Fab")
		)
		(fp_line
			(start -0.12065 -0.305054)
			(end -0.12065 -0.2794)
			(stroke
				(width 0.1)
				(type default)
			)
			(layer "F.Fab")
		)
		(fp_line
			(start -0.67945 0.3048)
			(end -0.67945 -0.305054)
			(stroke
				(width 0.1)
				(type default)
			)
			(layer "F.Fab")
		)
		(fp_line
			(start -0.67945 -0.305054)
			(end -0.12065 -0.305054)
			(stroke
				(width 0.1)
				(type default)
			)
			(layer "F.Fab")
		)
		(pad "1" smd circle
			(at -0.40005 0 180)
			(size 0 0)
			(layers "F.Cu" "F.Mask" "F.Paste")
			(net "SMB_BMC_GPU_EN")
		)
		(pad "2" smd circle
			(at 0.40005 0 180)
			(size 0 0)
			(layers "F.Cu" "F.Mask" "F.Paste")
			(net "SMB_BMC_GPU_EN_R3")
		)
	)
	(footprint ""
		(layer "F.Cu")
		(at 176.391062 -32.935672 90)
		(property "Reference" "PC2232"
			(at 0 0 90)
			(layer "F.SilkS")
			(hide yes)
			(effects
				(font
					(size 1.27 1.27)
				)
			)
		)
		(property "Value" ""
			(at 0 0 90)
			(layer "F.Fab")
			(effects
				(font
					(size 1.27 1.27)
				)
			)
		)
		(duplicate_pad_numbers_are_jumpers no)
		(fp_line
			(start 0.7874 -0.4064)
			(end 0.7874 0.4064)
			(stroke
				(width 0.1524)
				(type default)
			)
			(layer "F.SilkS")
		)
		(fp_line
			(start -0.7874 -0.4064)
			(end 0.7874 -0.4064)
			(stroke
				(width 0.1524)
				(type default)
			)
			(layer "F.SilkS")
		)
		(fp_line
			(start 0.7874 0.4064)
			(end -0.7874 0.4064)
			(stroke
				(width 0.1524)
				(type default)
			)
			(layer "F.SilkS")
		)
		(fp_line
			(start -0.7874 0.4064)
			(end -0.7874 -0.4064)
			(stroke
				(width 0.1524)
				(type default)
			)
			(layer "F.SilkS")
		)
		(fp_line
			(start -0.12065 -0.305054)
			(end -0.12065 -0.2794)
			(stroke
				(width 0.1)
				(type default)
			)
			(layer "F.Fab")
		)
		(fp_line
			(start -0.67945 -0.305054)
			(end -0.12065 -0.305054)
			(stroke
				(width 0.1)
				(type default)
			)
			(layer "F.Fab")
		)
		(fp_line
			(start 0.67945 -0.3048)
			(end 0.67945 0.3048)
			(stroke
				(width 0.1)
				(type default)
			)
			(layer "F.Fab")
		)
		(fp_line
			(start 0.12065 -0.3048)
			(end 0.67945 -0.3048)
			(stroke
				(width 0.1)
				(type default)
			)
			(layer "F.Fab")
		)
		(fp_line
			(start 0.12065 -0.2794)
			(end 0.12065 -0.3048)
			(stroke
				(width 0.1)
				(type default)
			)
			(layer "F.Fab")
		)
		(fp_line
			(start -0.12065 -0.2794)
			(end 0.12065 -0.2794)
			(stroke
				(width 0.1)
				(type default)
			)
			(layer "F.Fab")
		)
		(fp_line
			(start 0.120396 0.2794)
			(end -0.12065 0.2794)
			(stroke
				(width 0.1)
				(type default)
			)
			(layer "F.Fab")
		)
		(fp_line
			(start -0.12065 0.2794)
			(end -0.12065 0.3048)
			(stroke
				(width 0.1)
				(type default)
			)
			(layer "F.Fab")
		)
		(fp_line
			(start 0.67945 0.3048)
			(end 0.120396 0.3048)
			(stroke
				(width 0.1)
				(type default)
			)
			(layer "F.Fab")
		)
		(fp_line
			(start 0.120396 0.3048)
			(end 0.120396 0.2794)
			(stroke
				(width 0.1)
				(type default)
			)
			(layer "F.Fab")
		)
		(fp_line
			(start -0.12065 0.3048)
			(end -0.67945 0.3048)
			(stroke
				(width 0.1)
				(type default)
			)
			(layer "F.Fab")
		)
		(fp_line
			(start -0.67945 0.3048)
			(end -0.67945 -0.305054)
			(stroke
				(width 0.1)
				(type default)
			)
			(layer "F.Fab")
		)
		(pad "1" smd circle
			(at -0.40005 0 90)
			(size 0 0)
			(layers "F.Cu" "F.Mask" "F.Paste")
			(net "P12V_SCM_SS")
		)
		(pad "2" smd circle
			(at 0.40005 0 90)
			(size 0 0)
			(layers "F.Cu" "F.Mask" "F.Paste")
			(net "GND")
		)
	)
	(footprint ""
		(layer "F.Cu")
		(at 124.090176 -74.555096 90)
		(property "Reference" "PR8004"
			(at 0 0 90)
			(layer "F.SilkS")
			(hide yes)
			(effects
				(font
					(size 1.27 1.27)
				)
			)
		)
		(property "Value" ""
			(at 0 0 90)
			(layer "F.Fab")
			(effects
				(font
					(size 1.27 1.27)
				)
			)
		)
		(duplicate_pad_numbers_are_jumpers no)
		(fp_line
			(start 0.7874 -0.4064)
			(end 0.7874 0.4064)
			(stroke
				(width 0.1524)
				(type default)
			)
			(layer "F.SilkS")
		)
		(fp_line
			(start -0.7874 -0.4064)
			(end 0.7874 -0.4064)
			(stroke
				(width 0.1524)
				(type default)
			)
			(layer "F.SilkS")
		)
		(fp_line
			(start 0.7874 0.4064)
			(end -0.7874 0.4064)
			(stroke
				(width 0.1524)
				(type default)
			)
			(layer "F.SilkS")
		)
		(fp_line
			(start -0.7874 0.4064)
			(end -0.7874 -0.4064)
			(stroke
				(width 0.1524)
				(type default)
			)
			(layer "F.SilkS")
		)
		(fp_line
			(start -0.12065 -0.305054)
			(end -0.12065 -0.2794)
			(stroke
				(width 0.1)
				(type default)
			)
			(layer "F.Fab")
		)
		(fp_line
			(start -0.67945 -0.305054)
			(end -0.12065 -0.305054)
			(stroke
				(width 0.1)
				(type default)
			)
			(layer "F.Fab")
		)
		(fp_line
			(start 0.67945 -0.3048)
			(end 0.67945 0.3048)
			(stroke
				(width 0.1)
				(type default)
			)
			(layer "F.Fab")
		)
		(fp_line
			(start 0.12065 -0.3048)
			(end 0.67945 -0.3048)
			(stroke
				(width 0.1)
				(type default)
			)
			(layer "F.Fab")
		)
		(fp_line
			(start 0.12065 -0.2794)
			(end 0.12065 -0.3048)
			(stroke
				(width 0.1)
				(type default)
			)
			(layer "F.Fab")
		)
		(fp_line
			(start -0.12065 -0.2794)
			(end 0.12065 -0.2794)
			(stroke
				(width 0.1)
				(type default)
			)
			(layer "F.Fab")
		)
		(fp_line
			(start 0.120396 0.2794)
			(end -0.12065 0.2794)
			(stroke
				(width 0.1)
				(type default)
			)
			(layer "F.Fab")
		)
		(fp_line
			(start -0.12065 0.2794)
			(end -0.12065 0.3048)
			(stroke
				(width 0.1)
				(type default)
			)
			(layer "F.Fab")
		)
		(fp_line
			(start 0.67945 0.3048)
			(end 0.120396 0.3048)
			(stroke
				(width 0.1)
				(type default)
			)
			(layer "F.Fab")
		)
		(fp_line
			(start 0.120396 0.3048)
			(end 0.120396 0.2794)
			(stroke
				(width 0.1)
				(type default)
			)
			(layer "F.Fab")
		)
		(fp_line
			(start -0.12065 0.3048)
			(end -0.67945 0.3048)
			(stroke
				(width 0.1)
				(type default)
			)
			(layer "F.Fab")
		)
		(fp_line
			(start -0.67945 0.3048)
			(end -0.67945 -0.305054)
			(stroke
				(width 0.1)
				(type default)
			)
			(layer "F.Fab")
		)
		(pad "1" smd circle
			(at -0.40005 0 90)
			(size 0 0)
			(layers "F.Cu" "F.Mask" "F.Paste")
			(net "SW_P1V2_AUX_BT")
		)
		(pad "2" smd circle
			(at 0.40005 0 90)
			(size 0 0)
			(layers "F.Cu" "F.Mask" "F.Paste")
			(net "SW_P1V2_AUX_BT_R")
		)
	)
	(footprint ""
		(layer "F.Cu")
		(at 257.85953 -57.511442)
		(property "Reference" "R3955"
			(at 0 0 0)
			(layer "F.SilkS")
			(hide yes)
			(effects
				(font
					(size 1.27 1.27)
				)
			)
		)
		(property "Value" ""
			(at 0 0 0)
			(layer "F.Fab")
			(effects
				(font
					(size 1.27 1.27)
				)
			)
		)
		(duplicate_pad_numbers_are_jumpers no)
		(fp_line
			(start -0.7874 -0.4064)
			(end 0.7874 -0.4064)
			(stroke
				(width 0.1524)
				(type default)
			)
			(layer "F.SilkS")
		)
		(fp_line
			(start -0.7874 0.4064)
			(end -0.7874 -0.4064)
			(stroke
				(width 0.1524)
				(type default)
			)
			(layer "F.SilkS")
		)
		(fp_line
			(start 0.7874 -0.4064)
			(end 0.7874 0.4064)
			(stroke
				(width 0.1524)
				(type default)
			)
			(layer "F.SilkS")
		)
		(fp_line
			(start 0.7874 0.4064)
			(end -0.7874 0.4064)
			(stroke
				(width 0.1524)
				(type default)
			)
			(layer "F.SilkS")
		)
		(fp_line
			(start -0.67945 -0.305054)
			(end -0.12065 -0.305054)
			(stroke
				(width 0.1)
				(type default)
			)
			(layer "F.Fab")
		)
		(fp_line
			(start -0.67945 0.3048)
			(end -0.67945 -0.305054)
			(stroke
				(width 0.1)
				(type default)
			)
			(layer "F.Fab")
		)
		(fp_line
			(start -0.12065 -0.305054)
			(end -0.12065 -0.2794)
			(stroke
				(width 0.1)
				(type default)
			)
			(layer "F.Fab")
		)
		(fp_line
			(start -0.12065 -0.2794)
			(end 0.12065 -0.2794)
			(stroke
				(width 0.1)
				(type default)
			)
			(layer "F.Fab")
		)
		(fp_line
			(start -0.12065 0.2794)
			(end -0.12065 0.3048)
			(stroke
				(width 0.1)
				(type default)
			)
			(layer "F.Fab")
		)
		(fp_line
			(start -0.12065 0.3048)
			(end -0.67945 0.3048)
			(stroke
				(width 0.1)
				(type default)
			)
			(layer "F.Fab")
		)
		(fp_line
			(start 0.120396 0.2794)
			(end -0.12065 0.2794)
			(stroke
				(width 0.1)
				(type default)
			)
			(layer "F.Fab")
		)
		(fp_line
			(start 0.120396 0.3048)
			(end 0.120396 0.2794)
			(stroke
				(width 0.1)
				(type default)
			)
			(layer "F.Fab")
		)
		(fp_line
			(start 0.12065 -0.3048)
			(end 0.67945 -0.3048)
			(stroke
				(width 0.1)
				(type default)
			)
			(layer "F.Fab")
		)
		(fp_line
			(start 0.12065 -0.2794)
			(end 0.12065 -0.3048)
			(stroke
				(width 0.1)
				(type default)
			)
			(layer "F.Fab")
		)
		(fp_line
			(start 0.67945 -0.3048)
			(end 0.67945 0.3048)
			(stroke
				(width 0.1)
				(type default)
			)
			(layer "F.Fab")
		)
		(fp_line
			(start 0.67945 0.3048)
			(end 0.120396 0.3048)
			(stroke
				(width 0.1)
				(type default)
			)
			(layer "F.Fab")
		)
		(pad "1" smd circle
			(at -0.40005 0)
			(size 0 0)
			(layers "F.Cu" "F.Mask" "F.Paste")
			(net "P12V_E1S_IMON_0")
		)
		(pad "2" smd circle
			(at 0.40005 0)
			(size 0 0)
			(layers "F.Cu" "F.Mask" "F.Paste")
			(net "P12V_E1S_0_ISENSE_MPS_MAM")
		)
	)
	(footprint ""
		(layer "F.Cu")
		(at 123.443238 -41.17975 90)
		(property "Reference" "R6276"
			(at 0 0 90)
			(layer "F.SilkS")
			(hide yes)
			(effects
				(font
					(size 1.27 1.27)
				)
			)
		)
		(property "Value" ""
			(at 0 0 90)
			(layer "F.Fab")
			(effects
				(font
					(size 1.27 1.27)
				)
			)
		)
		(duplicate_pad_numbers_are_jumpers no)
		(fp_line
			(start 0.7874 -0.4064)
			(end 0.7874 0.4064)
			(stroke
				(width 0.1524)
				(type default)
			)
			(layer "F.SilkS")
		)
		(fp_line
			(start -0.7874 -0.4064)
			(end 0.7874 -0.4064)
			(stroke
				(width 0.1524)
				(type default)
			)
			(layer "F.SilkS")
		)
		(fp_line
			(start 0.7874 0.4064)
			(end -0.7874 0.4064)
			(stroke
				(width 0.1524)
				(type default)
			)
			(layer "F.SilkS")
		)
		(fp_line
			(start -0.7874 0.4064)
			(end -0.7874 -0.4064)
			(stroke
				(width 0.1524)
				(type default)
			)
			(layer "F.SilkS")
		)
		(fp_line
			(start -0.12065 -0.305054)
			(end -0.12065 -0.2794)
			(stroke
				(width 0.1)
				(type default)
			)
			(layer "F.Fab")
		)
		(fp_line
			(start -0.67945 -0.305054)
			(end -0.12065 -0.305054)
			(stroke
				(width 0.1)
				(type default)
			)
			(layer "F.Fab")
		)
		(fp_line
			(start 0.67945 -0.3048)
			(end 0.67945 0.3048)
			(stroke
				(width 0.1)
				(type default)
			)
			(layer "F.Fab")
		)
		(fp_line
			(start 0.12065 -0.3048)
			(end 0.67945 -0.3048)
			(stroke
				(width 0.1)
				(type default)
			)
			(layer "F.Fab")
		)
		(fp_line
			(start 0.12065 -0.2794)
			(end 0.12065 -0.3048)
			(stroke
				(width 0.1)
				(type default)
			)
			(layer "F.Fab")
		)
		(fp_line
			(start -0.12065 -0.2794)
			(end 0.12065 -0.2794)
			(stroke
				(width 0.1)
				(type default)
			)
			(layer "F.Fab")
		)
		(fp_line
			(start 0.120396 0.2794)
			(end -0.12065 0.2794)
			(stroke
				(width 0.1)
				(type default)
			)
			(layer "F.Fab")
		)
		(fp_line
			(start -0.12065 0.2794)
			(end -0.12065 0.3048)
			(stroke
				(width 0.1)
				(type default)
			)
			(layer "F.Fab")
		)
		(fp_line
			(start 0.67945 0.3048)
			(end 0.120396 0.3048)
			(stroke
				(width 0.1)
				(type default)
			)
			(layer "F.Fab")
		)
		(fp_line
			(start 0.120396 0.3048)
			(end 0.120396 0.2794)
			(stroke
				(width 0.1)
				(type default)
			)
			(layer "F.Fab")
		)
		(fp_line
			(start -0.12065 0.3048)
			(end -0.67945 0.3048)
			(stroke
				(width 0.1)
				(type default)
			)
			(layer "F.Fab")
		)
		(fp_line
			(start -0.67945 0.3048)
			(end -0.67945 -0.305054)
			(stroke
				(width 0.1)
				(type default)
			)
			(layer "F.Fab")
		)
		(pad "1" smd circle
			(at -0.40005 0 90)
			(size 0 0)
			(layers "F.Cu" "F.Mask" "F.Paste")
			(net "USB_HUB2_TI_VDD33_MRP_PRT_CTL4_GANGPWR")
		)
		(pad "2" smd circle
			(at 0.40005 0 90)
			(size 0 0)
			(layers "F.Cu" "F.Mask" "F.Paste")
			(net "USB_HUB2_MRP_PRT_CTL4_GANGPWR")
		)
	)
	(footprint ""
		(layer "F.Cu")
		(at 133.248146 -408.517344 -90)
		(property "Reference" "C6706"
			(at 0 0 270)
			(layer "F.SilkS")
			(hide yes)
			(effects
				(font
					(size 1.27 1.27)
				)
			)
		)
		(property "Value" ""
			(at 0 0 270)
			(layer "F.Fab")
			(effects
				(font
					(size 1.27 1.27)
				)
			)
		)
		(duplicate_pad_numbers_are_jumpers no)
		(fp_line
			(start -0.299974 0.150114)
			(end -0.299974 -0.150114)
			(stroke
				(width 0.1)
				(type default)
			)
			(layer "F.Fab")
		)
		(fp_line
			(start 0.299974 0.150114)
			(end -0.299974 0.150114)
			(stroke
				(width 0.1)
				(type default)
			)
			(layer "F.Fab")
		)
		(fp_line
			(start -0.299974 -0.150114)
			(end 0.299974 -0.150114)
			(stroke
				(width 0.1)
				(type default)
			)
			(layer "F.Fab")
		)
		(fp_line
			(start 0.299974 -0.150114)
			(end 0.299974 0.150114)
			(stroke
				(width 0.1)
				(type default)
			)
			(layer "F.Fab")
		)
		(pad "1" smd rect
			(at -0.2667 0 270)
			(size 0.3048 0.381)
			(layers "F.Cu" "F.Mask" "F.Paste")
			(net "P5E_CPU1_P2_TX_BUF_C_DN<6>")
		)
		(pad "2" smd rect
			(at 0.2667 0 270)
			(size 0.3048 0.381)
			(layers "F.Cu" "F.Mask" "F.Paste")
			(net "P5E_CPU1_P2_TX_BUF_DN<6>")
		)
	)
)
